(kicad_pcb
	(version 20260206)
	(generator "pcbnew")
	(generator_version "10.0")
	(general
		(thickness 1.6)
		(legacy_teardrops no)
	)
	(paper "A4")
	(title_block
		(title "01162023_DA0F0TEBIF0_F0T_Expander_BD_F_brd_V02_OCP.brd")
		(comment 1 "Grand Teton / footprints 5623-5630 of 9728")
	)
	(layers
		(0 "F.Cu" signal "TOP")
		(4 "In1.Cu" signal "GND")
		(6 "In2.Cu" signal "VCC")
		(8 "In3.Cu" signal "VCC1")
		(10 "In4.Cu" signal "GND1")
		(12 "In5.Cu" signal "IN1")
		(14 "In6.Cu" signal "GND2")
		(16 "In7.Cu" signal "IN2")
		(18 "In8.Cu" signal "GND3")
		(20 "In9.Cu" signal "IN3")
		(22 "In10.Cu" signal "GND4")
		(24 "In11.Cu" signal "IN4")
		(26 "In12.Cu" signal "GND5")
		(28 "In13.Cu" signal "IN5")
		(30 "In14.Cu" signal "GND6")
		(32 "In15.Cu" signal "IN6")
		(34 "In16.Cu" signal "GND7")
		(2 "B.Cu" signal "BOTTOM")
		(9 "F.Adhes" user "F.Adhesive")
		(11 "B.Adhes" user "B.Adhesive")
		(13 "F.Paste" user "Package Geometry/Pastemask Top")
		(15 "B.Paste" user "Package Geometry/Pastemask Bottom")
		(5 "F.SilkS" user "Ref Des/Silkscreen Top")
		(7 "B.SilkS" user "Ref Des/Silkscreen Bottom")
		(1 "F.Mask" user "Board Geometry/Soldermask Top")
		(3 "B.Mask" user "Board Geometry/Soldermask Bottom")
		(17 "Dwgs.User" user "User.Drawings")
		(19 "Cmts.User" user "User.Comments")
		(21 "Eco1.User" user "User.Eco1")
		(23 "Eco2.User" user "User.Eco2")
		(25 "Edge.Cuts" user "Board Geometry/Outline")
		(27 "Margin" user)
		(31 "F.CrtYd" user "Package Geometry/Place Bound Top")
		(29 "B.CrtYd" user "Package Geometry/Place Bound Bottom")
		(35 "F.Fab" user "Ref Des/Assembly Top")
		(33 "B.Fab" user "Ref Des/Assembly Bottom")
	)
	(footprint ""
		(layer "F.Cu")
		(at 264.775696 -36.915598 -90)
		(property "Reference" "R5571"
			(at 0 0 270)
			(layer "F.SilkS")
			(hide yes)
			(effects
				(font
					(size 1.27 1.27)
				)
			)
		)
		(property "Value" ""
			(at 0 0 270)
			(layer "F.Fab")
			(effects
				(font
					(size 1.27 1.27)
				)
			)
		)
		(duplicate_pad_numbers_are_jumpers no)
		(fp_line
			(start -0.7874 0.4064)
			(end -0.7874 -0.4064)
			(stroke
				(width 0.1524)
				(type default)
			)
			(layer "F.SilkS")
		)
		(fp_line
			(start 0.7874 0.4064)
			(end -0.7874 0.4064)
			(stroke
				(width 0.1524)
				(type default)
			)
			(layer "F.SilkS")
		)
		(fp_line
			(start -0.7874 -0.4064)
			(end 0.7874 -0.4064)
			(stroke
				(width 0.1524)
				(type default)
			)
			(layer "F.SilkS")
		)
		(fp_line
			(start 0.7874 -0.4064)
			(end 0.7874 0.4064)
			(stroke
				(width 0.1524)
				(type default)
			)
			(layer "F.SilkS")
		)
		(fp_line
			(start -0.67945 0.3048)
			(end -0.67945 -0.305054)
			(stroke
				(width 0.1)
				(type default)
			)
			(layer "F.Fab")
		)
		(fp_line
			(start -0.12065 0.3048)
			(end -0.67945 0.3048)
			(stroke
				(width 0.1)
				(type default)
			)
			(layer "F.Fab")
		)
		(fp_line
			(start 0.120396 0.3048)
			(end 0.120396 0.2794)
			(stroke
				(width 0.1)
				(type default)
			)
			(layer "F.Fab")
		)
		(fp_line
			(start 0.67945 0.3048)
			(end 0.120396 0.3048)
			(stroke
				(width 0.1)
				(type default)
			)
			(layer "F.Fab")
		)
		(fp_line
			(start -0.12065 0.2794)
			(end -0.12065 0.3048)
			(stroke
				(width 0.1)
				(type default)
			)
			(layer "F.Fab")
		)
		(fp_line
			(start 0.120396 0.2794)
			(end -0.12065 0.2794)
			(stroke
				(width 0.1)
				(type default)
			)
			(layer "F.Fab")
		)
		(fp_line
			(start -0.12065 -0.2794)
			(end 0.12065 -0.2794)
			(stroke
				(width 0.1)
				(type default)
			)
			(layer "F.Fab")
		)
		(fp_line
			(start 0.12065 -0.2794)
			(end 0.12065 -0.3048)
			(stroke
				(width 0.1)
				(type default)
			)
			(layer "F.Fab")
		)
		(fp_line
			(start 0.12065 -0.3048)
			(end 0.67945 -0.3048)
			(stroke
				(width 0.1)
				(type default)
			)
			(layer "F.Fab")
		)
		(fp_line
			(start 0.67945 -0.3048)
			(end 0.67945 0.3048)
			(stroke
				(width 0.1)
				(type default)
			)
			(layer "F.Fab")
		)
		(fp_line
			(start -0.67945 -0.305054)
			(end -0.12065 -0.305054)
			(stroke
				(width 0.1)
				(type default)
			)
			(layer "F.Fab")
		)
		(fp_line
			(start -0.12065 -0.305054)
			(end -0.12065 -0.2794)
			(stroke
				(width 0.1)
				(type default)
			)
			(layer "F.Fab")
		)
		(pad "1" smd circle
			(at -0.40005 0 270)
			(size 0 0)
			(layers "F.Cu" "F.Mask" "F.Paste")
			(net "PRSNT_SSD9_R1_N")
		)
		(pad "2" smd circle
			(at 0.40005 0 270)
			(size 0 0)
			(layers "F.Cu" "F.Mask" "F.Paste")
			(net "PRSNT_SSD9_R_N")
		)
	)
	(footprint ""
		(layer "F.Cu")
		(at 82.661506 -152.511252 180)
		(property "Reference" "C5"
			(at 0 0 180)
			(layer "F.SilkS")
			(hide yes)
			(effects
				(font
					(size 1.27 1.27)
				)
			)
		)
		(property "Value" ""
			(at 0 0 180)
			(layer "F.Fab")
			(effects
				(font
					(size 1.27 1.27)
				)
			)
		)
		(duplicate_pad_numbers_are_jumpers no)
		(fp_line
			(start 0.299974 0.150114)
			(end -0.299974 0.150114)
			(stroke
				(width 0.1)
				(type default)
			)
			(layer "F.Fab")
		)
		(fp_line
			(start 0.299974 -0.150114)
			(end 0.299974 0.150114)
			(stroke
				(width 0.1)
				(type default)
			)
			(layer "F.Fab")
		)
		(fp_line
			(start -0.299974 0.150114)
			(end -0.299974 -0.150114)
			(stroke
				(width 0.1)
				(type default)
			)
			(layer "F.Fab")
		)
		(fp_line
			(start -0.299974 -0.150114)
			(end 0.299974 -0.150114)
			(stroke
				(width 0.1)
				(type default)
			)
			(layer "F.Fab")
		)
		(pad "1" smd rect
			(at -0.2667 0 180)
			(size 0.3048 0.381)
			(layers "F.Cu" "F.Mask" "F.Paste")
			(net "P5E_PEX0_STN0_TX_DP<13>")
		)
		(pad "2" smd rect
			(at 0.2667 0 180)
			(size 0.3048 0.381)
			(layers "F.Cu" "F.Mask" "F.Paste")
			(net "P5E_PEX0_STN0_TX_C_DP<13>")
		)
	)
	(footprint ""
		(layer "F.Cu")
		(at 55.356506 -155.819856 90)
		(property "Reference" "R46"
			(at 0 0 90)
			(layer "F.SilkS")
			(hide yes)
			(effects
				(font
					(size 1.27 1.27)
				)
			)
		)
		(property "Value" ""
			(at 0 0 90)
			(layer "F.Fab")
			(effects
				(font
					(size 1.27 1.27)
				)
			)
		)
		(duplicate_pad_numbers_are_jumpers no)
		(fp_line
			(start 0.7874 -0.4064)
			(end 0.7874 0.4064)
			(stroke
				(width 0.1524)
				(type default)
			)
			(layer "F.SilkS")
		)
		(fp_line
			(start -0.7874 -0.4064)
			(end 0.7874 -0.4064)
			(stroke
				(width 0.1524)
				(type default)
			)
			(layer "F.SilkS")
		)
		(fp_line
			(start 0.7874 0.4064)
			(end -0.7874 0.4064)
			(stroke
				(width 0.1524)
				(type default)
			)
			(layer "F.SilkS")
		)
		(fp_line
			(start -0.7874 0.4064)
			(end -0.7874 -0.4064)
			(stroke
				(width 0.1524)
				(type default)
			)
			(layer "F.SilkS")
		)
		(fp_line
			(start -0.12065 -0.305054)
			(end -0.12065 -0.2794)
			(stroke
				(width 0.1)
				(type default)
			)
			(layer "F.Fab")
		)
		(fp_line
			(start -0.67945 -0.305054)
			(end -0.12065 -0.305054)
			(stroke
				(width 0.1)
				(type default)
			)
			(layer "F.Fab")
		)
		(fp_line
			(start 0.67945 -0.3048)
			(end 0.67945 0.3048)
			(stroke
				(width 0.1)
				(type default)
			)
			(layer "F.Fab")
		)
		(fp_line
			(start 0.12065 -0.3048)
			(end 0.67945 -0.3048)
			(stroke
				(width 0.1)
				(type default)
			)
			(layer "F.Fab")
		)
		(fp_line
			(start 0.12065 -0.2794)
			(end 0.12065 -0.3048)
			(stroke
				(width 0.1)
				(type default)
			)
			(layer "F.Fab")
		)
		(fp_line
			(start -0.12065 -0.2794)
			(end 0.12065 -0.2794)
			(stroke
				(width 0.1)
				(type default)
			)
			(layer "F.Fab")
		)
		(fp_line
			(start 0.120396 0.2794)
			(end -0.12065 0.2794)
			(stroke
				(width 0.1)
				(type default)
			)
			(layer "F.Fab")
		)
		(fp_line
			(start -0.12065 0.2794)
			(end -0.12065 0.3048)
			(stroke
				(width 0.1)
				(type default)
			)
			(layer "F.Fab")
		)
		(fp_line
			(start 0.67945 0.3048)
			(end 0.120396 0.3048)
			(stroke
				(width 0.1)
				(type default)
			)
			(layer "F.Fab")
		)
		(fp_line
			(start 0.120396 0.3048)
			(end 0.120396 0.2794)
			(stroke
				(width 0.1)
				(type default)
			)
			(layer "F.Fab")
		)
		(fp_line
			(start -0.12065 0.3048)
			(end -0.67945 0.3048)
			(stroke
				(width 0.1)
				(type default)
			)
			(layer "F.Fab")
		)
		(fp_line
			(start -0.67945 0.3048)
			(end -0.67945 -0.305054)
			(stroke
				(width 0.1)
				(type default)
			)
			(layer "F.Fab")
		)
		(pad "1" smd circle
			(at -0.40005 0 90)
			(size 0 0)
			(layers "F.Cu" "F.Mask" "F.Paste")
			(net "RST_NIC0_PERST1_R_N")
		)
		(pad "2" smd circle
			(at 0.40005 0 90)
			(size 0 0)
			(layers "F.Cu" "F.Mask" "F.Paste")
			(net "RST_HP_NIC0_BUF_N")
		)
	)
	(footprint ""
		(layer "F.Cu")
		(at 242.730528 -142.035276 180)
		(property "Reference" "PC801"
			(at 0 0 180)
			(layer "F.SilkS")
			(hide yes)
			(effects
				(font
					(size 1.27 1.27)
				)
			)
		)
		(property "Value" ""
			(at 0 0 180)
			(layer "F.Fab")
			(effects
				(font
					(size 1.27 1.27)
				)
			)
		)
		(duplicate_pad_numbers_are_jumpers no)
		(fp_line
			(start 1.524 0.762)
			(end -1.524 0.762)
			(stroke
				(width 0.1524)
				(type default)
			)
			(layer "F.SilkS")
		)
		(fp_line
			(start 1.524 -0.762)
			(end 1.524 0.762)
			(stroke
				(width 0.1524)
				(type default)
			)
			(layer "F.SilkS")
		)
		(fp_line
			(start -1.524 0.762)
			(end -1.524 -0.762)
			(stroke
				(width 0.1524)
				(type default)
			)
			(layer "F.SilkS")
		)
		(fp_line
			(start -1.524 -0.762)
			(end 1.524 -0.762)
			(stroke
				(width 0.1524)
				(type default)
			)
			(layer "F.SilkS")
		)
		(fp_line
			(start 1.1049 0.724916)
			(end 1.1049 -0.724916)
			(stroke
				(width 0.1)
				(type default)
			)
			(layer "F.Fab")
		)
		(fp_line
			(start 1.1049 -0.724916)
			(end -1.1049 -0.724916)
			(stroke
				(width 0.1)
				(type default)
			)
			(layer "F.Fab")
		)
		(fp_line
			(start -1.1049 0.724916)
			(end 1.1049 0.724916)
			(stroke
				(width 0.1)
				(type default)
			)
			(layer "F.Fab")
		)
		(fp_line
			(start -1.1049 -0.724916)
			(end -1.1049 0.724916)
			(stroke
				(width 0.1)
				(type default)
			)
			(layer "F.Fab")
		)
		(pad "1" smd rect
			(at -0.889 0)
			(size 1.016 1.27)
			(layers "F.Cu" "F.Mask" "F.Paste")
			(net "P12V_NIC4_R")
		)
		(pad "2" smd rect
			(at 0.889 0)
			(size 1.016 1.27)
			(layers "F.Cu" "F.Mask" "F.Paste")
			(net "GND")
		)
	)
	(footprint ""
		(layer "F.Cu")
		(at 80.875124 -64.102234 180)
		(property "Reference" "PR6914"
			(at 0 0 180)
			(layer "F.SilkS")
			(hide yes)
			(effects
				(font
					(size 1.27 1.27)
				)
			)
		)
		(property "Value" ""
			(at 0 0 180)
			(layer "F.Fab")
			(effects
				(font
					(size 1.27 1.27)
				)
			)
		)
		(duplicate_pad_numbers_are_jumpers no)
		(fp_line
			(start 0.7874 0.4064)
			(end -0.7874 0.4064)
			(stroke
				(width 0.1524)
				(type default)
			)
			(layer "F.SilkS")
		)
		(fp_line
			(start 0.7874 -0.4064)
			(end 0.7874 0.4064)
			(stroke
				(width 0.1524)
				(type default)
			)
			(layer "F.SilkS")
		)
		(fp_line
			(start -0.7874 0.4064)
			(end -0.7874 -0.4064)
			(stroke
				(width 0.1524)
				(type default)
			)
			(layer "F.SilkS")
		)
		(fp_line
			(start -0.7874 -0.4064)
			(end 0.7874 -0.4064)
			(stroke
				(width 0.1524)
				(type default)
			)
			(layer "F.SilkS")
		)
		(fp_line
			(start 0.67945 0.3048)
			(end 0.120396 0.3048)
			(stroke
				(width 0.1)
				(type default)
			)
			(layer "F.Fab")
		)
		(fp_line
			(start 0.67945 -0.3048)
			(end 0.67945 0.3048)
			(stroke
				(width 0.1)
				(type default)
			)
			(layer "F.Fab")
		)
		(fp_line
			(start 0.12065 -0.2794)
			(end 0.12065 -0.3048)
			(stroke
				(width 0.1)
				(type default)
			)
			(layer "F.Fab")
		)
		(fp_line
			(start 0.12065 -0.3048)
			(end 0.67945 -0.3048)
			(stroke
				(width 0.1)
				(type default)
			)
			(layer "F.Fab")
		)
		(fp_line
			(start 0.120396 0.3048)
			(end 0.120396 0.2794)
			(stroke
				(width 0.1)
				(type default)
			)
			(layer "F.Fab")
		)
		(fp_line
			(start 0.120396 0.2794)
			(end -0.12065 0.2794)
			(stroke
				(width 0.1)
				(type default)
			)
			(layer "F.Fab")
		)
		(fp_line
			(start -0.12065 0.3048)
			(end -0.67945 0.3048)
			(stroke
				(width 0.1)
				(type default)
			)
			(layer "F.Fab")
		)
		(fp_line
			(start -0.12065 0.2794)
			(end -0.12065 0.3048)
			(stroke
				(width 0.1)
				(type default)
			)
			(layer "F.Fab")
		)
		(fp_line
			(start -0.12065 -0.2794)
			(end 0.12065 -0.2794)
			(stroke
				(width 0.1)
				(type default)
			)
			(layer "F.Fab")
		)
		(fp_line
			(start -0.12065 -0.305054)
			(end -0.12065 -0.2794)
			(stroke
				(width 0.1)
				(type default)
			)
			(layer "F.Fab")
		)
		(fp_line
			(start -0.67945 0.3048)
			(end -0.67945 -0.305054)
			(stroke
				(width 0.1)
				(type default)
			)
			(layer "F.Fab")
		)
		(fp_line
			(start -0.67945 -0.305054)
			(end -0.12065 -0.305054)
			(stroke
				(width 0.1)
				(type default)
			)
			(layer "F.Fab")
		)
		(pad "1" smd circle
			(at -0.40005 0 180)
			(size 0 0)
			(layers "F.Cu" "F.Mask" "F.Paste")
			(net "P12V_SSD3_PG_G1")
		)
		(pad "2" smd circle
			(at 0.40005 0 180)
			(size 0 0)
			(layers "F.Cu" "F.Mask" "F.Paste")
			(net "GND")
		)
	)
	(footprint ""
		(layer "F.Cu")
		(at 133.892544 -32.739584 180)
		(property "Reference" "C278"
			(at 0 0 180)
			(layer "F.SilkS")
			(hide yes)
			(effects
				(font
					(size 1.27 1.27)
				)
			)
		)
		(property "Value" ""
			(at 0 0 180)
			(layer "F.Fab")
			(effects
				(font
					(size 1.27 1.27)
				)
			)
		)
		(duplicate_pad_numbers_are_jumpers no)
		(fp_line
			(start 0.299974 0.150114)
			(end -0.299974 0.150114)
			(stroke
				(width 0.1)
				(type default)
			)
			(layer "F.Fab")
		)
		(fp_line
			(start 0.299974 -0.150114)
			(end 0.299974 0.150114)
			(stroke
				(width 0.1)
				(type default)
			)
			(layer "F.Fab")
		)
		(fp_line
			(start -0.299974 0.150114)
			(end -0.299974 -0.150114)
			(stroke
				(width 0.1)
				(type default)
			)
			(layer "F.Fab")
		)
		(fp_line
			(start -0.299974 -0.150114)
			(end 0.299974 -0.150114)
			(stroke
				(width 0.1)
				(type default)
			)
			(layer "F.Fab")
		)
		(pad "1" smd rect
			(at -0.2667 0 180)
			(size 0.3048 0.381)
			(layers "F.Cu" "F.Mask" "F.Paste")
			(net "P5E_PEX1_STN2_TX_DP<46>")
		)
		(pad "2" smd rect
			(at 0.2667 0 180)
			(size 0.3048 0.381)
			(layers "F.Cu" "F.Mask" "F.Paste")
			(net "P5E_PEX1_STN2_TX_C_DP<46>")
		)
	)
	(footprint ""
		(layer "F.Cu")
		(at 136.708388 -343.952322 90)
		(property "Reference" "C2251"
			(at 0 0 90)
			(layer "F.SilkS")
			(hide yes)
			(effects
				(font
					(size 1.27 1.27)
				)
			)
		)
		(property "Value" ""
			(at 0 0 90)
			(layer "F.Fab")
			(effects
				(font
					(size 1.27 1.27)
				)
			)
		)
		(duplicate_pad_numbers_are_jumpers no)
		(fp_line
			(start 0.299974 -0.150114)
			(end 0.299974 0.150114)
			(stroke
				(width 0.1)
				(type default)
			)
			(layer "F.Fab")
		)
		(fp_line
			(start -0.299974 -0.150114)
			(end 0.299974 -0.150114)
			(stroke
				(width 0.1)
				(type default)
			)
			(layer "F.Fab")
		)
		(fp_line
			(start 0.299974 0.150114)
			(end -0.299974 0.150114)
			(stroke
				(width 0.1)
				(type default)
			)
			(layer "F.Fab")
		)
		(fp_line
			(start -0.299974 0.150114)
			(end -0.299974 -0.150114)
			(stroke
				(width 0.1)
				(type default)
			)
			(layer "F.Fab")
		)
		(pad "1" smd rect
			(at -0.2667 0 90)
			(size 0.3048 0.381)
			(layers "F.Cu" "F.Mask" "F.Paste")
			(net "P5E_PEX1_STN5_TX_DP<91>")
		)
		(pad "2" smd rect
			(at 0.2667 0 90)
			(size 0.3048 0.381)
			(layers "F.Cu" "F.Mask" "F.Paste")
			(net "P5E_PEX1_STN5_TX_C_DP<91>")
		)
	)
	(footprint ""
		(layer "F.Cu")
		(at 406.36444 -140.6398 180)
		(property "Reference" "R344"
			(at 0 0 180)
			(layer "F.SilkS")
			(hide yes)
			(effects
				(font
					(size 1.27 1.27)
				)
			)
		)
		(property "Value" ""
			(at 0 0 180)
			(layer "F.Fab")
			(effects
				(font
					(size 1.27 1.27)
				)
			)
		)
		(duplicate_pad_numbers_are_jumpers no)
		(fp_line
			(start 0.7874 0.4064)
			(end -0.7874 0.4064)
			(stroke
				(width 0.1524)
				(type default)
			)
			(layer "F.SilkS")
		)
		(fp_line
			(start 0.7874 -0.4064)
			(end 0.7874 0.4064)
			(stroke
				(width 0.1524)
				(type default)
			)
			(layer "F.SilkS")
		)
		(fp_line
			(start -0.7874 0.4064)
			(end -0.7874 -0.4064)
			(stroke
				(width 0.1524)
				(type default)
			)
			(layer "F.SilkS")
		)
		(fp_line
			(start -0.7874 -0.4064)
			(end 0.7874 -0.4064)
			(stroke
				(width 0.1524)
				(type default)
			)
			(layer "F.SilkS")
		)
		(fp_line
			(start 0.67945 0.3048)
			(end 0.120396 0.3048)
			(stroke
				(width 0.1)
				(type default)
			)
			(layer "F.Fab")
		)
		(fp_line
			(start 0.67945 -0.3048)
			(end 0.67945 0.3048)
			(stroke
				(width 0.1)
				(type default)
			)
			(layer "F.Fab")
		)
		(fp_line
			(start 0.12065 -0.2794)
			(end 0.12065 -0.3048)
			(stroke
				(width 0.1)
				(type default)
			)
			(layer "F.Fab")
		)
		(fp_line
			(start 0.12065 -0.3048)
			(end 0.67945 -0.3048)
			(stroke
				(width 0.1)
				(type default)
			)
			(layer "F.Fab")
		)
		(fp_line
			(start 0.120396 0.3048)
			(end 0.120396 0.2794)
			(stroke
				(width 0.1)
				(type default)
			)
			(layer "F.Fab")
		)
		(fp_line
			(start 0.120396 0.2794)
			(end -0.12065 0.2794)
			(stroke
				(width 0.1)
				(type default)
			)
			(layer "F.Fab")
		)
		(fp_line
			(start -0.12065 0.3048)
			(end -0.67945 0.3048)
			(stroke
				(width 0.1)
				(type default)
			)
			(layer "F.Fab")
		)
		(fp_line
			(start -0.12065 0.2794)
			(end -0.12065 0.3048)
			(stroke
				(width 0.1)
				(type default)
			)
			(layer "F.Fab")
		)
		(fp_line
			(start -0.12065 -0.2794)
			(end 0.12065 -0.2794)
			(stroke
				(width 0.1)
				(type default)
			)
			(layer "F.Fab")
		)
		(fp_line
			(start -0.12065 -0.305054)
			(end -0.12065 -0.2794)
			(stroke
				(width 0.1)
				(type default)
			)
			(layer "F.Fab")
		)
		(fp_line
			(start -0.67945 0.3048)
			(end -0.67945 -0.305054)
			(stroke
				(width 0.1)
				(type default)
			)
			(layer "F.Fab")
		)
		(fp_line
			(start -0.67945 -0.305054)
			(end -0.12065 -0.305054)
			(stroke
				(width 0.1)
				(type default)
			)
			(layer "F.Fab")
		)
		(pad "1" smd circle
			(at -0.40005 0 180)
			(size 0 0)
			(layers "F.Cu" "F.Mask" "F.Paste")
			(net "RST_SMB_NIC6_MUX_ISO_N")
		)
		(pad "2" smd circle
			(at 0.40005 0 180)
			(size 0 0)
			(layers "F.Cu" "F.Mask" "F.Paste")
			(net "GND")
		)
	)
)
